# S9S_MB_2U (Grand Teton) — schematic parts with pin connectivity, parts 1606–1606 of 6093; source: Cadence DE-HDL packaged netlist (pstxprt.dat, pstxnet.dat, pstchip.dat)

J13  SCONN288_ADR50017P130CC  SCONN288_ADR50017-P130CC IO  pkg DDR288S_1-1VXB  page 94
  1  VIN_BULK0  POWER  = P12V_S3_AUX_CPU0_NVDIMM
  2  RFU0  TRI  = TP_CHG_CPU0_DIMM1_FRU_0
  3  VIN_MGMT  POWER  = P3V3_AUX
  4  HSCL  IN  = I3C_SPD_DDREFGH_CPU0_LVC1_SCL_4
  5  HSDA  BI  = I3C_SPD_DDREFGH_CPU0_LVC1_SDA
  6  VSS0  POWER  = GND
  7  DQ0_A  BI  = M_G_CPU0_SA_DQ<0>
  8  VSS1  POWER  = GND
  9  DQ1_A  BI  = M_G_CPU0_SA_DQ<1>
  10  VSS2  POWER  = GND
  11  DQS0_A_T  BI  = M_G_CPU0_SA_DQS_DP<0>
  12  DQS0_A_C  BI  = M_G_CPU0_SA_DQS_DN<0>
  13  VSS3  POWER  = GND
  14  DQ4_A  BI  = M_G_CPU0_SA_DQ<4>
  15  VSS4  POWER  = GND
  16  DQ5_A  BI  = M_G_CPU0_SA_DQ<5>
  17  VSS5  POWER  = GND
  18  DQ8_A  BI  = M_G_CPU0_SA_DQ<8>
  19  VSS6  POWER  = GND
  20  DQ9_A  BI  = M_G_CPU0_SA_DQ<9>
  21  VSS7  POWER  = GND
  22  DQS1_A_T  BI  = M_G_CPU0_SA_DQS_DP<1>
  23  DQS1_A_C  BI  = M_G_CPU0_SA_DQS_DN<1>
  24  VSS8  POWER  = GND
  25  DQ12_A  BI  = M_G_CPU0_SA_DQ<12>
  26  VSS9  POWER  = GND
  27  DQ13_A  BI  = M_G_CPU0_SA_DQ<13>
  28  VSS10  POWER  = GND
  29  DQ16_A  BI  = M_G_CPU0_SA_DQ<16>
  30  VSS11  POWER  = GND
  31  DQ17_A  BI  = M_G_CPU0_SA_DQ<17>
  32  VSS12  POWER  = GND
  33  DQS2_A_T  BI  = M_G_CPU0_SA_DQS_DP<2>
  34  DQS2_A_C  BI  = M_G_CPU0_SA_DQS_DN<2>
  35  VSS13  POWER  = GND
  36  DQ20_A  BI  = M_G_CPU0_SA_DQ<20>
  37  VSS14  POWER  = GND
  38  DQ21_A  BI  = M_G_CPU0_SA_DQ<21>
  39  VSS15  POWER  = GND
  40  DQ24_A  BI  = M_G_CPU0_SA_DQ<24>
  41  VSS16  POWER  = GND
  42  DQ25_A  BI  = M_G_CPU0_SA_DQ<25>
  43  VSS17  POWER  = GND
  44  DQS3_A_T  BI  = M_G_CPU0_SA_DQS_DP<3>
  45  DQS3_A_C  BI  = M_G_CPU0_SA_DQS_DN<3>
  46  VSS18  POWER  = GND
  47  DQ28_A  BI  = M_G_CPU0_SA_DQ<28>
  48  VSS19  POWER  = GND
  49  DQ29_A  BI  = M_G_CPU0_SA_DQ<29>
  50  VSS20  POWER  = GND
  51  CB0_A  BI  = M_G_CPU0_SA_CB<0>
  52  VSS21  POWER  = GND
  53  CB1_A  BI  = M_G_CPU0_SA_CB<1>
  54  VSS22  POWER  = GND
  55  DQS4_A_T  BI  = M_G_CPU0_SA_DQS_DP<4>
  56  DQS4_A_C  BI  = M_G_CPU0_SA_DQS_DN<4>
  57  VSS23  POWER  = GND
  58  CB4_A  BI  = M_G_CPU0_SA_CB<4>
  59  VSS24  POWER  = GND
  60  CB5_A  BI  = M_G_CPU0_SA_CB<5>
  61  VSS25  POWER  = GND
  62  ALERT_N  OUT  = M_G_CPU0_ALERT_N
  63  VSS26  POWER  = GND
  64  CS0_A_N  IN  = M_G_CPU0_SA_CS_N<0>
  65  VSS27  POWER  = GND
  66  CA0_A  IN  = M_G_CPU0_SA_CA<0>
  67  VSS28  POWER  = GND
  68  CA2_A  IN  = M_G_CPU0_SA_CA<2>
  69  VSS29  POWER  = GND
  70  CA4_A  IN  = M_G_CPU0_SA_CA<4>
  71  VSS30  POWER  = GND
  72  CA6_A  IN  = M_G_CPU0_SA_CA<6>
  73  VSS31  POWER  = GND
  74  PAR_A  IN  = M_G_CPU0_SA_PAR
  75  VSS32  POWER  = GND
  76  CA0_B  IN  = M_G_CPU0_SB_CA<0>
  77  VSS33  POWER  = GND
  78  CA2_B  IN  = M_G_CPU0_SB_CA<2>
  79  VSS34  POWER  = GND
  80  CA4_B  IN  = M_G_CPU0_SB_CA<4>
  81  VSS35  POWER  = GND
  82  CA6_B  IN  = M_G_CPU0_SB_CA<6>
  83  VSS36  POWER  = GND
  84  CS0_B_N  IN  = M_G_CPU0_SB_CS_N<0>
  85  VSS37  POWER  = GND
  86  \lbd||rsp_a_n\  OUT  = M_G_CPU0_SA_RSP<0>
  87  \lbs||rsp_b_n\  OUT  = M_G_CPU0_SB_RSP<0>
  88  VSS38  POWER  = GND
  89  CB4_B  BI  = M_G_CPU0_SB_CB<4>
  90  VSS39  POWER  = GND
  91  CB5_B  BI  = M_G_CPU0_SB_CB<5>
  92  VSS40  POWER  = GND
  93  \dqs9_b_t||tdqs9_b_t||dbi4_b_n\  BI  = M_G_CPU0_SB_DQS_DP<9>
  94  \dqs9_b_c||tdqs9_b_c\  BI  = M_G_CPU0_SB_DQS_DN<9>
  95  VSS41  POWER  = GND
  96  CB0_B  BI  = M_G_CPU0_SB_CB<0>
  97  VSS42  POWER  = GND
  98  CB1_B  BI  = M_G_CPU0_SB_CB<1>
  99  VSS43  POWER  = GND
  100  DQ0_B  BI  = M_G_CPU0_SB_DQ<0>
  101  VSS44  POWER  = GND
  102  DQ1_B  BI  = M_G_CPU0_SB_DQ<1>
  103  VSS45  POWER  = GND
  104  DQS0_B_T  BI  = M_G_CPU0_SB_DQS_DP<0>
  105  DQS0_B_C  BI  = M_G_CPU0_SB_DQS_DN<0>
  106  VSS46  POWER  = GND
  107  DQ4_B  BI  = M_G_CPU0_SB_DQ<4>
  108  VSS47  POWER  = GND
  109  DQ5_B  BI  = M_G_CPU0_SB_DQ<5>
  110  VSS48  POWER  = GND
  111  DQ8_B  BI  = M_G_CPU0_SB_DQ<8>
  112  VSS49  POWER  = GND
  113  DQ9_B  BI  = M_G_CPU0_SB_DQ<9>
  114  VSS50  POWER  = GND
  115  DQS1_B_T  BI  = M_G_CPU0_SB_DQS_DP<1>
  116  DQS1_B_C  BI  = M_G_CPU0_SB_DQS_DN<1>
  117  VSS51  POWER  = GND
  118  DQ12_B  BI  = M_G_CPU0_SB_DQ<12>
  119  VSS52  POWER  = GND
  120  DQ13_B  BI  = M_G_CPU0_SB_DQ<13>
  121  VSS53  POWER  = GND
  122  DQ16_B  BI  = M_G_CPU0_SB_DQ<16>
  123  VSS54  POWER  = GND
  124  DQ17_B  BI  = M_G_CPU0_SB_DQ<17>
  125  VSS55  POWER  = GND
  126  DQS2_B_T  BI  = M_G_CPU0_SB_DQS_DP<2>
  127  DQS2_B_C  BI  = M_G_CPU0_SB_DQS_DN<2>
  128  VSS56  POWER  = GND
  129  DQ20_B  BI  = M_G_CPU0_SB_DQ<20>
  130  VSS57  POWER  = GND
  131  DQ21_B  BI  = M_G_CPU0_SB_DQ<21>
  132  VSS58  POWER  = GND
  133  DQ24_B  BI  = M_G_CPU0_SB_DQ<24>
  134  VSS59  POWER  = GND
  135  DQ25_B  BI  = M_G_CPU0_SB_DQ<25>
  136  VSS60  POWER  = GND
  137  DQS3_B_T  BI  = M_G_CPU0_SB_DQS_DP<3>
  138  DQS3_B_C  BI  = M_G_CPU0_SB_DQS_DN<3>
  139  VSS61  POWER  = GND
  140  DQ28_B  BI  = M_G_CPU0_SB_DQ<28>
  141  VSS62  POWER  = GND
  142  DQ29_B  BI  = M_G_CPU0_SB_DQ<29>
  143  VSS63  POWER  = GND
  144  RFU1  TRI  = TP_CHG_CPU0_DIMM1_FRU_1
  145  VIN_BULK1  POWER  = P12V_S3_AUX_CPU0_NVDIMM
  146  VIN_BULK2  POWER  = P12V_S3_AUX_CPU0_NVDIMM
  147  \pwr_good||fail_n\  BI  = PWRGD_CHG_CPU0_DIMM1
  148  HSA  IN  = PD_CHG_CPU0_DIMM1_SAA
  149  RFU2  TRI  = TP_CHG_CPU0_DIMM1_FRU_2
  150  RFU3  TRI  = TP_CHG_CPU0_DIMM1_FRU_3
  151  VSS64  POWER  = GND
  152  DQ2_A  BI  = M_G_CPU0_SA_DQ<2>
  153  VSS65  POWER  = GND
  154  DQ3_A  BI  = M_G_CPU0_SA_DQ<3>
  155  VSS66  POWER  = GND
  156  \dqs5_a_c||tdqs5_a_c||dqs5_a_t||tdqs5_a_t\  BI  = M_G_CPU0_SA_DQS_DN<5>
  157  \dqs5_a_t||tdqs5_a_t\  BI  = M_G_CPU0_SA_DQS_DP<5>
  158  VSS67  POWER  = GND
  159  DQ6_A  BI  = M_G_CPU0_SA_DQ<6>
  160  VSS68  POWER  = GND
  161  DQ7_A  BI  = M_G_CPU0_SA_DQ<7>
  162  VSS69  POWER  = GND
  163  DQ10_A  BI  = M_G_CPU0_SA_DQ<10>
  164  VSS70  POWER  = GND
  165  DQ11_A  BI  = M_G_CPU0_SA_DQ<11>
  166  VSS71  POWER  = GND
  167  \dqs6_a_c||tdqs6_a_c||dqs6_a_t||tdqs6_a_t\  BI  = M_G_CPU0_SA_DQS_DN<6>
  168  \dqs6_a_t||tdqs6_a_t\  BI  = M_G_CPU0_SA_DQS_DP<6>
  169  VSS72  POWER  = GND
  170  DQ14_A  BI  = M_G_CPU0_SA_DQ<14>
  171  VSS73  POWER  = GND
  172  DQ15_A  BI  = M_G_CPU0_SA_DQ<15>
  173  VSS74  POWER  = GND
  174  DQ18_A  BI  = M_G_CPU0_SA_DQ<18>
  175  VSS75  POWER  = GND
  176  DQ19_A  BI  = M_G_CPU0_SA_DQ<19>
  177  VSS76  POWER  = GND
  178  \dqs7_a_c||tdqs7_a_c\  BI  = M_G_CPU0_SA_DQS_DN<7>
  179  \dqs7_a_t||tdqs7_a_t\  BI  = M_G_CPU0_SA_DQS_DP<7>
  180  VSS77  POWER  = GND
  181  DQ22_A  BI  = M_G_CPU0_SA_DQ<22>
  182  VSS78  POWER  = GND
  183  DQ23_A  BI  = M_G_CPU0_SA_DQ<23>
  184  VSS79  POWER  = GND
  185  DQ26_A  BI  = M_G_CPU0_SA_DQ<26>
  186  VSS80  POWER  = GND
  187  DQ27_A  BI  = M_G_CPU0_SA_DQ<27>
  188  VSS81  POWER  = GND
  189  \dqs8_a_c||tdqs8_a_c\  BI  = M_G_CPU0_SA_DQS_DN<8>
  190  \dqs8_a_t||tdqs8_a_t\  BI  = M_G_CPU0_SA_DQS_DP<8>
  191  VSS82  POWER  = GND
  192  DQ30_A  BI  = M_G_CPU0_SA_DQ<30>
  193  VSS83  POWER  = GND
  194  DQ31_A  BI  = M_G_CPU0_SA_DQ<31>
  195  VSS84  POWER  = GND
  196  CB2_A  BI  = M_G_CPU0_SA_CB<2>
  197  VSS85  POWER  = GND
  198  CB3_A  BI  = M_G_CPU0_SA_CB<3>
  199  VSS86  POWER  = GND
  200  \dqs9_a_c||tdqs9_a_c\  BI  = M_G_CPU0_SA_DQS_DN<9>
  201  \dqs9_a_t||tdqs9_a_t\  BI  = M_G_CPU0_SA_DQS_DP<9>
  202  VSS87  POWER  = GND
  203  CB6_A  BI  = M_G_CPU0_SA_CB<6>
  204  VSS88  POWER  = GND
  205  CB7_A  BI  = M_G_CPU0_SA_CB<7>
  206  VSS89  POWER  = GND
  207  RESET_N  IN  = RST_M_GH_CPU0_FPGA_N
  208  VSS90  POWER  = GND
  209  CS1_A_N  IN  = M_G_CPU0_SA_CS_N<1>
  210  VSS91  POWER  = GND
  211  CA1_A  IN  = M_G_CPU0_SA_CA<1>
  212  VSS92  POWER  = GND
  213  CA3_A  IN  = M_G_CPU0_SA_CA<3>
  214  VSS93  POWER  = GND
  215  CA5_A  IN  = M_G_CPU0_SA_CA<5>
  216  VSS94  POWER  = GND
  217  CK_T  IN  = M_G_CPU0_CLK_DP<0>
  218  CK_C  IN  = M_G_CPU0_CLK_DN<0>
  219  VSS95  POWER  = GND
  220  RFU4  TRI  = TP_CHG_CPU0_DIMM1_FRU_4
  221  CA1_B  IN  = M_G_CPU0_SB_CA<1>
  222  VSS96  POWER  = GND
  223  CA3_B  IN  = M_G_CPU0_SB_CA<3>
  224  VSS97  POWER  = GND
  225  CA5_B  IN  = M_G_CPU0_SB_CA<5>
  226  VSS98  POWER  = GND
  227  PAR_B  IN  = M_G_CPU0_SB_PAR
  228  VSS99  POWER  = GND
  229  CS1_B_N  IN  = M_G_CPU0_SB_CS_N<1>
  230  VSS100  POWER  = GND
  231  RFU5  TRI  = TP_CHG_CPU0_DIMM1_FRU_5
  232  RFU6  TRI  = TP_CHG_CPU0_DIMM1_FRU_6
  233  VSS101  POWER  = GND
  234  CB6_B  BI  = M_G_CPU0_SB_CB<6>
  235  VSS102  POWER  = GND
  236  CB7_B  BI  = M_G_CPU0_SB_CB<7>
  237  VSS103  POWER  = GND
  238  DQS4_B_C  BI  = M_G_CPU0_SB_DQS_DN<4>
  239  DQS4_B_T  BI  = M_G_CPU0_SB_DQS_DP<4>
  240  VSS104  POWER  = GND
  241  CB2_B  BI  = M_G_CPU0_SB_CB<2>
  242  VSS105  POWER  = GND
  243  CB3_B  BI  = M_G_CPU0_SB_CB<3>
  244  VSS106  POWER  = GND
  245  DQ2_B  BI  = M_G_CPU0_SB_DQ<2>
  246  VSS107  POWER  = GND
  247  DQ3_B  BI  = M_G_CPU0_SB_DQ<3>
  248  VSS108  POWER  = GND
  249  \dqs5_b_c||tdqs5_b_c\  BI  = M_G_CPU0_SB_DQS_DN<5>
  250  \dqs5_b_t||tdqs5_b_t\  BI  = M_G_CPU0_SB_DQS_DP<5>
  251  VSS109  POWER  = GND
  252  DQ6_B  BI  = M_G_CPU0_SB_DQ<6>
  253  VSS110  POWER  = GND
  254  DQ7_B  BI  = M_G_CPU0_SB_DQ<7>
  255  VSS111  POWER  = GND
  256  DQ10_B  BI  = M_G_CPU0_SB_DQ<10>
  257  VSS112  POWER  = GND
  258  DQ11_B  BI  = M_G_CPU0_SB_DQ<11>
  259  VSS113  POWER  = GND
  260  \dqs6_b_c||tdqs6_b_c\  BI  = M_G_CPU0_SB_DQS_DN<6>
  261  \dqs6_b_t||tdqs6_b_t\  BI  = M_G_CPU0_SB_DQS_DP<6>
  262  VSS114  POWER  = GND
  263  DQ14_B  BI  = M_G_CPU0_SB_DQ<14>
  264  VSS115  POWER  = GND
  265  DQ15_B  BI  = M_G_CPU0_SB_DQ<15>
  266  VSS116  POWER  = GND
  267  DQ18_B  BI  = M_G_CPU0_SB_DQ<18>
  268  VSS117  POWER  = GND
  269  DQ19_B  BI  = M_G_CPU0_SB_DQ<19>
  270  VSS118  POWER  = GND
  271  \dqs7_b_c||tdqs7_b_c\  BI  = M_G_CPU0_SB_DQS_DN<7>
  272  \dqs7_b_t||tdqs7_b_t\  BI  = M_G_CPU0_SB_DQS_DP<7>
  273  VSS119  POWER  = GND
  274  DQ22_B  BI  = M_G_CPU0_SB_DQ<22>
  275  VSS120  POWER  = GND
  276  DQ23_B  BI  = M_G_CPU0_SB_DQ<23>
  277  VSS121  POWER  = GND
  278  DQ26_B  BI  = M_G_CPU0_SB_DQ<26>
  279  VSS122  POWER  = GND
  280  DQ27_B  BI  = M_G_CPU0_SB_DQ<27>
  281  VSS123  POWER  = GND
  282  \dqs8_b_c||tdqs8_b_c\  BI  = M_G_CPU0_SB_DQS_DN<8>
  283  \dqs8_b_t||tdqs8_b_t\  BI  = M_G_CPU0_SB_DQS_DP<8>
  284  VSS124  POWER  = GND
  285  DQ30_B  BI  = M_G_CPU0_SB_DQ<30>
  286  VSS125  POWER  = GND
  287  DQ31_B  BI  = M_G_CPU0_SB_DQ<31>
  288  VSS126  POWER  = GND
  G1  G1  POWER  = GND
  G2  G2  POWER  = GND
  G3  G3  POWER  = GND
